# T6G (Grand Teton) — schematic netlist excerpt (pin names and nets, part order shuffled) for the footprints in the layout excerpt that follows; sources: Cadence DE-HDL packaged netlist, KiCad conversion of 04192023_DAF0TMB3IC0_F0TG_MB_C_brd_V02_OCP.brd

U56  ISL28022FRZT  ISL28022FRZ-T IC  pkg QFN16_TH_0-5_3X3XH  page 357
  A1  = INA230_7_A1
  A0  = INA230_7_A0
  \ext_clk||int\  = P12V_OCP_V3_2_ADC_ALERT_R
  \sda||smbdat\  = SMB_INA230_7_3V3AUX_SDA_R1
  \scl|||smbclk\  = SMB_INA230_7_3V3AUX_SCL_R1
  NC0  = NC_INA230_7_NC0
  NC1  = NC_INA230_7_NC1
  NC2  = NC_INA230_7_NC2
  VCC  = P3V3_AUX
  GND  = GND
  VBUS  = P12V_OCP_V3_2
  VINM  = VSENSE_P12V_INA230_7_INN
  VINP  = VSENSE_P12V_INA230_7_INP
  NC3  = NC_INA230_7_NC3
  NC4  = NC_INA230_7_NC4
  NC5  = NC_INA230_7_NC5
  TH_GND  = GND

(kicad_pcb
	(version 20260206)
	(generator "pcbnew")
	(generator_version "10.0")
	(general
		(thickness 1.6)
		(legacy_teardrops no)
	)
	(paper "A4")
	(title_block
		(title "04192023_DAF0TMB3IC0_F0TG_MB_C_brd_V02_OCP.brd")
		(comment 1 "Grand Teton / footprints 232-232 of 8354")
	)
	(layers
		(0 "F.Cu" signal "TOP")
		(4 "In1.Cu" signal "GND")
		(6 "In2.Cu" signal "IN1")
		(8 "In3.Cu" signal "GND1")
		(10 "In4.Cu" signal "IN2")
		(12 "In5.Cu" signal "GND2")
		(14 "In6.Cu" signal "IN3")
		(16 "In7.Cu" signal "GND3")
		(18 "In8.Cu" signal "VCC")
		(20 "In9.Cu" signal "VCC1")
		(22 "In10.Cu" signal "GND4")
		(24 "In11.Cu" signal "IN4")
		(26 "In12.Cu" signal "GND5")
		(28 "In13.Cu" signal "IN5")
		(30 "In14.Cu" signal "GND6")
		(32 "In15.Cu" signal "IN6")
		(34 "In16.Cu" signal "GND7")
		(2 "B.Cu" signal "BOTTOM")
		(9 "F.Adhes" user "F.Adhesive")
		(11 "B.Adhes" user "B.Adhesive")
		(13 "F.Paste" user "Package Geometry/Pastemask Top")
		(15 "B.Paste" user "Package Geometry/Pastemask Bottom")
		(5 "F.SilkS" user "Ref Des/Silkscreen Top")
		(7 "B.SilkS" user "Ref Des/Silkscreen Bottom")
		(1 "F.Mask" user "Board Geometry/Soldermask Top")
		(3 "B.Mask" user "Board Geometry/Soldermask Bottom")
		(17 "Dwgs.User" user "User.Drawings")
		(19 "Cmts.User" user "User.Comments")
		(21 "Eco1.User" user "User.Eco1")
		(23 "Eco2.User" user "User.Eco2")
		(25 "Edge.Cuts" user "Board Geometry/Outline")
		(27 "Margin" user)
		(31 "F.CrtYd" user "Package Geometry/Place Bound Top")
		(29 "B.CrtYd" user "Package Geometry/Place Bound Bottom")
		(35 "F.Fab" user "Ref Des/Assembly Top")
		(33 "B.Fab" user "Ref Des/Assembly Bottom")
	)
	(footprint ""
		(layer "F.Cu")
		(at 23.229316 -39.824914)
		(property "Reference" "U56"
			(at -1.567942 -4.057904 0)
			(unlocked yes)
			(layer "F.SilkS")
			(effects
				(font
					(size 0.7874 0.5842)
					(thickness 0.1524)
				)
			)
		)
		(property "Value" ""
			(at 0 0 0)
			(layer "F.Fab")
			(effects
				(font
					(size 1.27 1.27)
				)
			)
		)
		(duplicate_pad_numbers_are_jumpers no)
		(fp_line
			(start -1.500124 -1.500124)
			(end -1.004062 -1.500124)
			(stroke
				(width 0.1524)
				(type default)
			)
			(layer "F.SilkS")
		)
		(fp_line
			(start -1.500124 -1.004062)
			(end -1.500124 -1.500124)
			(stroke
				(width 0.1524)
				(type default)
			)
			(layer "F.SilkS")
		)
		(fp_line
			(start -1.500124 1.500124)
			(end -1.500124 1.004062)
			(stroke
				(width 0.1524)
				(type default)
			)
			(layer "F.SilkS")
		)
		(fp_line
			(start -1.004062 1.500124)
			(end -1.500124 1.500124)
			(stroke
				(width 0.1524)
				(type default)
			)
			(layer "F.SilkS")
		)
		(fp_line
			(start 1.004062 -1.500124)
			(end 1.500124 -1.500124)
			(stroke
				(width 0.1524)
				(type default)
			)
			(layer "F.SilkS")
		)
		(fp_line
			(start 1.500124 -1.500124)
			(end 1.500124 -1.004062)
			(stroke
				(width 0.1524)
				(type default)
			)
			(layer "F.SilkS")
		)
		(fp_line
			(start 1.500124 1.004062)
			(end 1.500124 1.500124)
			(stroke
				(width 0.1524)
				(type default)
			)
			(layer "F.SilkS")
		)
		(fp_line
			(start 1.500124 1.500124)
			(end 1.004062 1.500124)
			(stroke
				(width 0.1524)
				(type default)
			)
			(layer "F.SilkS")
		)
		(fp_poly
			(pts
				(xy -2.335784 -2.746502) (xy -3.134868 -2.119122) (xy -2.107946 -1.633728)
			)
			(stroke
				(width 0)
				(type default)
			)
			(fill yes)
			(layer "F.SilkS")
		)
		(fp_line
			(start -1.500124 -1.500124)
			(end 1.500124 -1.500124)
			(stroke
				(width 0.1)
				(type default)
			)
			(layer "F.Fab")
		)
		(fp_line
			(start -1.500124 1.500124)
			(end -1.500124 -1.500124)
			(stroke
				(width 0.1)
				(type default)
			)
			(layer "F.Fab")
		)
		(fp_line
			(start 1.500124 -1.500124)
			(end 1.500124 1.500124)
			(stroke
				(width 0.1)
				(type default)
			)
			(layer "F.Fab")
		)
		(fp_line
			(start 1.500124 1.500124)
			(end -1.500124 1.500124)
			(stroke
				(width 0.1)
				(type default)
			)
			(layer "F.Fab")
		)
		(fp_poly
			(pts
				(xy -2.847848 -1.258062) (xy -2.847848 -0.242062) (xy -1.831848 -0.750062)
			)
			(stroke
				(width 0)
				(type default)
			)
			(fill yes)
			(layer "F.Fab")
		)
		(pad "1" smd rect
			(at -1.400048 -0.750062 270)
			(size 0.2286 0.6096)
			(layers "F.Cu" "F.Mask" "F.Paste")
			(net "INA230_7_A1")
		)
		(pad "2" smd rect
			(at -1.400048 -0.249936 270)
			(size 0.2286 0.6096)
			(layers "F.Cu" "F.Mask" "F.Paste")
			(net "INA230_7_A0")
		)
		(pad "3" smd rect
			(at -1.400048 0.249936 270)
			(size 0.2286 0.6096)
			(layers "F.Cu" "F.Mask" "F.Paste")
			(net "P12V_OCP_V3_2_ADC_ALERT_R")
		)
		(pad "4" smd rect
			(at -1.400048 0.750062 270)
			(size 0.2286 0.6096)
			(layers "F.Cu" "F.Mask" "F.Paste")
			(net "SMB_INA230_7_3V3AUX_SDA_R1")
		)
		(pad "5" smd rect
			(at -0.750062 1.400048)
			(size 0.2286 0.6096)
			(layers "F.Cu" "F.Mask" "F.Paste")
			(net "SMB_INA230_7_3V3AUX_SCL_R1")
		)
		(pad "6" smd rect
			(at -0.249936 1.400048)
			(size 0.2286 0.6096)
			(layers "F.Cu" "F.Mask" "F.Paste")
			(net "NC_INA230_7_NC0")
		)
		(pad "7" smd rect
			(at 0.249936 1.400048)
			(size 0.2286 0.6096)
			(layers "F.Cu" "F.Mask" "F.Paste")
			(net "NC_INA230_7_NC1")
		)
		(pad "8" smd rect
			(at 0.750062 1.400048)
			(size 0.2286 0.6096)
			(layers "F.Cu" "F.Mask" "F.Paste")
			(net "NC_INA230_7_NC2")
		)
		(pad "9" smd rect
			(at 1.400048 0.750062 270)
			(size 0.2286 0.6096)
			(layers "F.Cu" "F.Mask" "F.Paste")
			(net "P3V3_AUX")
		)
		(pad "10" smd rect
			(at 1.400048 0.249936 270)
			(size 0.2286 0.6096)
			(layers "F.Cu" "F.Mask" "F.Paste")
			(net "GND")
		)
		(pad "11" smd rect
			(at 1.400048 -0.249936 270)
			(size 0.2286 0.6096)
			(layers "F.Cu" "F.Mask" "F.Paste")
			(net "P12V_OCP_V3_2")
		)
		(pad "12" smd rect
			(at 1.400048 -0.750062 270)
			(size 0.2286 0.6096)
			(layers "F.Cu" "F.Mask" "F.Paste")
			(net "VSENSE_P12V_INA230_7_INN")
		)
		(pad "13" smd rect
			(at 0.750062 -1.400048)
			(size 0.2286 0.6096)
			(layers "F.Cu" "F.Mask" "F.Paste")
			(net "VSENSE_P12V_INA230_7_INP")
		)
		(pad "14" smd rect
			(at 0.249936 -1.400048)
			(size 0.2286 0.6096)
			(layers "F.Cu" "F.Mask" "F.Paste")
			(net "NC_INA230_7_NC3")
		)
		(pad "15" smd rect
			(at -0.249936 -1.400048)
			(size 0.2286 0.6096)
			(layers "F.Cu" "F.Mask" "F.Paste")
			(net "NC_INA230_7_NC4")
		)
		(pad "16" smd rect
			(at -0.750062 -1.400048)
			(size 0.2286 0.6096)
			(layers "F.Cu" "F.Mask" "F.Paste")
			(net "NC_INA230_7_NC5")
		)
		(pad "TH" smd rect
			(at 0 0)
			(size 1.7018 1.7018)
			(layers "F.Cu" "F.Mask" "F.Paste")
			(net "GND")
		)
		(zone
			(layer "F.Cu")
			(hatch none 0.5)
			(connect_pads
				(clearance 0)
			)
			(min_thickness 0.25)
			(keepout
				(tracks not_allowed)
				(vias allowed)
				(pads allowed)
				(copperpour not_allowed)
				(footprints allowed)
			)
			(placement
				(enabled no)
				(sheetname "")
			)
			(fill
				(thermal_gap 0.5)
				(thermal_bridge_width 0.5)
				(island_removal_mode 0)
			)
			(polygon
				(pts
					(xy 22.184868 -39.850314) (xy 22.184868 -40.869362) (xy 24.273764 -40.869362) (xy 24.273764 -38.780466)
					(xy 22.184868 -38.780466) (xy 22.184868 -39.824914) (xy 22.327616 -39.824914) (xy 22.327616 -38.923214)
					(xy 24.131016 -38.923214) (xy 24.131016 -40.726614) (xy 22.327616 -40.726614) (xy 22.327616 -39.850314)
				)
			)
		)
	)
)
